(kicad_pcb
	(version 20260206)
	(generator "pcbnew")
	(generator_version "10.0")
	(general
		(thickness 1.6)
		(legacy_teardrops no)
	)
	(paper "A4")
	(title_block
		(title "03242023_DA0F0TMBIJ0_F0T_Motherboard_J_brd_V01_OCP.brd")
		(comment 1 "Grand Teton / footprints 5718-5722 of 6105")
	)
	(layers
		(0 "F.Cu" signal "TOP")
		(4 "In1.Cu" signal "GND")
		(6 "In2.Cu" signal "IN1")
		(8 "In3.Cu" signal "GND1")
		(10 "In4.Cu" signal "IN2")
		(12 "In5.Cu" signal "GND2")
		(14 "In6.Cu" signal "IN3")
		(16 "In7.Cu" signal "GND3")
		(18 "In8.Cu" signal "VCC")
		(20 "In9.Cu" signal "VCC1")
		(22 "In10.Cu" signal "GND4")
		(24 "In11.Cu" signal "IN4")
		(26 "In12.Cu" signal "GND5")
		(28 "In13.Cu" signal "IN5")
		(30 "In14.Cu" signal "GND6")
		(32 "In15.Cu" signal "IN6")
		(34 "In16.Cu" signal "GND7")
		(2 "B.Cu" signal "BOTTOM")
		(9 "F.Adhes" user "F.Adhesive")
		(11 "B.Adhes" user "B.Adhesive")
		(13 "F.Paste" user "Package Geometry/Pastemask Top")
		(15 "B.Paste" user "Package Geometry/Pastemask Bottom")
		(5 "F.SilkS" user "Ref Des/Silkscreen Top")
		(7 "B.SilkS" user "Ref Des/Silkscreen Bottom")
		(1 "F.Mask" user "Board Geometry/Soldermask Top")
		(3 "B.Mask" user "Board Geometry/Soldermask Bottom")
		(17 "Dwgs.User" user "User.Drawings")
		(19 "Cmts.User" user "User.Comments")
		(21 "Eco1.User" user "User.Eco1")
		(23 "Eco2.User" user "User.Eco2")
		(25 "Edge.Cuts" user "Board Geometry/Outline")
		(27 "Margin" user)
		(31 "F.CrtYd" user "Package Geometry/Place Bound Top")
		(29 "B.CrtYd" user "Package Geometry/Place Bound Bottom")
		(35 "F.Fab" user "Ref Des/Assembly Top")
		(33 "B.Fab" user "Ref Des/Assembly Bottom")
	)
	(footprint ""
		(layer "B.Cu")
		(at 12.076684 -112.319308 -90)
		(property "Reference" "U5201"
			(at -3.494532 -1.880616 0)
			(unlocked yes)
			(layer "B.SilkS")
			(effects
				(font
					(size 0.7874 0.5842)
					(thickness 0.1524)
				)
				(justify left mirror)
			)
		)
		(property "Value" ""
			(at 0 0 90)
			(layer "B.Fab")
			(effects
				(font
					(size 1.27 1.27)
				)
				(justify mirror)
			)
		)
		(duplicate_pad_numbers_are_jumpers no)
		(fp_line
			(start -1.2446 1.2446)
			(end -1.2446 0.479044)
			(stroke
				(width 0.1524)
				(type default)
			)
			(layer "B.SilkS")
		)
		(fp_line
			(start 1.2446 1.2446)
			(end -1.2446 1.2446)
			(stroke
				(width 0.1524)
				(type default)
			)
			(layer "B.SilkS")
		)
		(fp_line
			(start 1.2446 0.593344)
			(end 1.2446 1.2446)
			(stroke
				(width 0.1524)
				(type default)
			)
			(layer "B.SilkS")
		)
		(fp_line
			(start -1.2446 -0.506476)
			(end -1.2446 -1.2446)
			(stroke
				(width 0.1524)
				(type default)
			)
			(layer "B.SilkS")
		)
		(fp_line
			(start -1.2446 -1.2446)
			(end 1.2446 -1.2446)
			(stroke
				(width 0.1524)
				(type default)
			)
			(layer "B.SilkS")
		)
		(fp_line
			(start 1.2446 -1.2446)
			(end 1.2446 -0.592836)
			(stroke
				(width 0.1524)
				(type default)
			)
			(layer "B.SilkS")
		)
		(fp_poly
			(pts
				(xy 1.416812 -0.430022) (xy 1.688592 -1.246124) (xy 2.23266 -0.702056)
			)
			(stroke
				(width 0)
				(type default)
			)
			(fill yes)
			(layer "B.SilkS")
		)
		(fp_line
			(start -0.824992 0.824992)
			(end -0.824992 -0.824992)
			(stroke
				(width 0.1)
				(type default)
			)
			(layer "B.Fab")
		)
		(fp_line
			(start 0.824992 0.824992)
			(end -0.824992 0.824992)
			(stroke
				(width 0.1)
				(type default)
			)
			(layer "B.Fab")
		)
		(fp_line
			(start -0.824992 -0.824992)
			(end 0.824992 -0.824992)
			(stroke
				(width 0.1)
				(type default)
			)
			(layer "B.Fab")
		)
		(fp_line
			(start 0.824992 -0.824992)
			(end 0.824992 0.824992)
			(stroke
				(width 0.1)
				(type default)
			)
			(layer "B.Fab")
		)
		(fp_poly
			(pts
				(xy 1.389634 -0.199898) (xy 2.159 0.184658) (xy 2.159 -0.584708)
			)
			(stroke
				(width 0)
				(type default)
			)
			(fill yes)
			(layer "B.Fab")
		)
		(pad "1" smd rect
			(at 0.700024 -0.199898 180)
			(size 0.1778 0.8128)
			(layers "B.Cu" "B.Mask" "B.Paste")
			(net "USB2_HUB_BUF_SWB_R_DN")
		)
		(pad "2" smd rect
			(at 0.700024 0.199898 180)
			(size 0.1778 0.8128)
			(layers "B.Cu" "B.Mask" "B.Paste")
			(net "USB2_HUB_BUF_SWB_R_DP")
		)
		(pad "3" smd rect
			(at 0.599948 0.8001 90)
			(size 0.1778 0.6096)
			(layers "B.Cu" "B.Mask" "B.Paste")
			(net "TP_USB2_TEST")
		)
		(pad "4" smd rect
			(at 0.199898 0.8001 90)
			(size 0.1778 0.6096)
			(layers "B.Cu" "B.Mask" "B.Paste")
			(net "TP_USB2_CD")
		)
		(pad "5" smd rect
			(at -0.199898 0.8001 90)
			(size 0.1778 0.6096)
			(layers "B.Cu" "B.Mask" "B.Paste")
			(net "PD_U5201_RSTN")
		)
		(pad "6" smd rect
			(at -0.599948 0.8001 90)
			(size 0.1778 0.6096)
			(layers "B.Cu" "B.Mask" "B.Paste")
			(net "PD_U5201_EQ")
		)
		(pad "7" smd rect
			(at -0.700024 0.199898 180)
			(size 0.1778 0.8128)
			(layers "B.Cu" "B.Mask" "B.Paste")
			(net "USB2_HUB_BUF_SWB_R_DP")
		)
		(pad "8" smd rect
			(at -0.700024 -0.199898 180)
			(size 0.1778 0.8128)
			(layers "B.Cu" "B.Mask" "B.Paste")
			(net "USB2_HUB_BUF_SWB_R_DN")
		)
		(pad "9" smd rect
			(at -0.599948 -0.8001 90)
			(size 0.1778 0.6096)
			(layers "B.Cu" "B.Mask" "B.Paste")
			(net "TP_USB2_ENA_HS")
		)
		(pad "10" smd rect
			(at -0.199898 -0.8001 90)
			(size 0.1778 0.6096)
			(layers "B.Cu" "B.Mask" "B.Paste")
			(net "GND")
		)
		(pad "11" smd rect
			(at 0.199898 -0.8001 90)
			(size 0.1778 0.6096)
			(layers "B.Cu" "B.Mask" "B.Paste")
			(net "PD_U5201_VREG")
		)
		(pad "12" smd rect
			(at 0.599948 -0.8001 90)
			(size 0.1778 0.6096)
			(layers "B.Cu" "B.Mask" "B.Paste")
			(net "P3V3_AUX")
		)
	)
	(footprint ""
		(layer "B.Cu")
		(at 343.166192 -64.088264 90)
		(property "Reference" "C163"
			(at 0 0 90)
			(layer "B.SilkS")
			(hide yes)
			(effects
				(font
					(size 1.27 1.27)
				)
				(justify mirror)
			)
		)
		(property "Value" ""
			(at 0 0 90)
			(layer "B.Fab")
			(effects
				(font
					(size 1.27 1.27)
				)
				(justify mirror)
			)
		)
		(duplicate_pad_numbers_are_jumpers no)
		(fp_line
			(start 0.299974 -0.150114)
			(end -0.299974 -0.150114)
			(stroke
				(width 0.1)
				(type default)
			)
			(layer "B.Fab")
		)
		(fp_line
			(start -0.299974 -0.150114)
			(end -0.299974 0.150114)
			(stroke
				(width 0.1)
				(type default)
			)
			(layer "B.Fab")
		)
		(fp_line
			(start 0.299974 0.150114)
			(end 0.299974 -0.150114)
			(stroke
				(width 0.1)
				(type default)
			)
			(layer "B.Fab")
		)
		(fp_line
			(start -0.299974 0.150114)
			(end 0.299974 0.150114)
			(stroke
				(width 0.1)
				(type default)
			)
			(layer "B.Fab")
		)
		(pad "1" smd rect
			(at 0.2667 0 270)
			(size 0.3048 0.381)
			(layers "B.Cu" "B.Mask" "B.Paste")
			(net "DMI_CPU0_PCH_RX_C_DN<3>")
		)
		(pad "2" smd rect
			(at -0.2667 0 270)
			(size 0.3048 0.381)
			(layers "B.Cu" "B.Mask" "B.Paste")
			(net "DMI_CPU0_PCH_RX_DN<3>")
		)
	)
	(footprint ""
		(layer "B.Cu")
		(at 47.80661 -344.935556 -90)
		(property "Reference" "PC413_P1_2"
			(at 0 0 90)
			(layer "B.SilkS")
			(hide yes)
			(effects
				(font
					(size 1.27 1.27)
				)
				(justify mirror)
			)
		)
		(property "Value" ""
			(at 0 0 90)
			(layer "B.Fab")
			(effects
				(font
					(size 1.27 1.27)
				)
				(justify mirror)
			)
		)
		(duplicate_pad_numbers_are_jumpers no)
		(fp_line
			(start -1.524 0.762)
			(end 1.524 0.762)
			(stroke
				(width 0.1524)
				(type default)
			)
			(layer "B.SilkS")
		)
		(fp_line
			(start 1.524 0.762)
			(end 1.524 -0.762)
			(stroke
				(width 0.1524)
				(type default)
			)
			(layer "B.SilkS")
		)
		(fp_line
			(start -1.524 -0.762)
			(end -1.524 0.762)
			(stroke
				(width 0.1524)
				(type default)
			)
			(layer "B.SilkS")
		)
		(fp_line
			(start 1.524 -0.762)
			(end -1.524 -0.762)
			(stroke
				(width 0.1524)
				(type default)
			)
			(layer "B.SilkS")
		)
		(fp_line
			(start -1.1049 0.724916)
			(end -1.1049 -0.724916)
			(stroke
				(width 0.1)
				(type default)
			)
			(layer "B.Fab")
		)
		(fp_line
			(start 1.1049 0.724916)
			(end -1.1049 0.724916)
			(stroke
				(width 0.1)
				(type default)
			)
			(layer "B.Fab")
		)
		(fp_line
			(start -1.1049 -0.724916)
			(end 1.1049 -0.724916)
			(stroke
				(width 0.1)
				(type default)
			)
			(layer "B.Fab")
		)
		(fp_line
			(start 1.1049 -0.724916)
			(end 1.1049 0.724916)
			(stroke
				(width 0.1)
				(type default)
			)
			(layer "B.Fab")
		)
		(pad "1" smd rect
			(at 0.889 0 270)
			(size 1.016 1.27)
			(layers "B.Cu" "B.Mask" "B.Paste")
			(net "PVCCFA_EHV_FIVRA_CPU1")
		)
		(pad "2" smd rect
			(at -0.889 0 270)
			(size 1.016 1.27)
			(layers "B.Cu" "B.Mask" "B.Paste")
			(net "GND")
		)
	)
	(footprint ""
		(layer "B.Cu")
		(at 329.240388 2.923794)
		(property "Reference" "J119"
			(at 4.361942 1.521206 270)
			(unlocked yes)
			(layer "B.SilkS")
			(effects
				(font
					(size 0.7874 0.5842)
					(thickness 0.1524)
				)
				(justify left mirror)
			)
		)
		(property "Value" ""
			(at 0 0 0)
			(layer "B.Fab")
			(effects
				(font
					(size 1.27 1.27)
				)
				(justify mirror)
			)
		)
		(duplicate_pad_numbers_are_jumpers no)
		(fp_line
			(start -1.2192 -2.1082)
			(end -1.2192 2.1082)
			(stroke
				(width 0.1524)
				(type default)
			)
			(layer "B.SilkS")
		)
		(fp_line
			(start -1.2192 2.1082)
			(end 1.2192 2.1082)
			(stroke
				(width 0.1524)
				(type default)
			)
			(layer "B.SilkS")
		)
		(fp_line
			(start 1.2192 -2.1082)
			(end -1.2192 -2.1082)
			(stroke
				(width 0.1524)
				(type default)
			)
			(layer "B.SilkS")
		)
		(fp_line
			(start 1.2192 2.1082)
			(end 1.2192 -2.1082)
			(stroke
				(width 0.1524)
				(type default)
			)
			(layer "B.SilkS")
		)
		(pad "" np_thru_hole circle
			(at -3.4671 -1.27 270)
			(size 1.0414 1.0414)
			(drill 1.0414)
			(layers "*.Cu" "*.Mask")
			(clearance 0.381)
			(thermal_gap 0.381)
		)
		(pad "" np_thru_hole circle
			(at -3.4671 1.27 270)
			(size 1.0414 1.0414)
			(drill 1.0414)
			(layers "*.Cu" "*.Mask")
			(clearance 0.381)
			(thermal_gap 0.381)
		)
		(pad "" np_thru_hole circle
			(at 2.8829 -1.27 270)
			(size 1.0414 1.0414)
			(drill 1.0414)
			(layers "*.Cu" "*.Mask")
			(clearance 0.381)
			(thermal_gap 0.381)
		)
		(pad "" np_thru_hole circle
			(at 2.8829 1.27 270)
			(size 1.0414 1.0414)
			(drill 1.0414)
			(layers "*.Cu" "*.Mask")
			(clearance 0.381)
			(thermal_gap 0.381)
		)
		(pad "1" smd rect
			(at -0.8255 -0.249936 270)
			(size 0.3048 0.508)
			(layers "B.Cu" "B.Mask" "B.Paste")
			(net "DELTA_L_85_10INCH_IN6_DP")
		)
		(pad "2" smd rect
			(at -0.8255 0.249936 270)
			(size 0.3048 0.508)
			(layers "B.Cu" "B.Mask" "B.Paste")
			(net "DELTA_L_85_10INCH_IN6_DN")
		)
		(pad "3" smd circle
			(at 0 0 180)
			(size 0 0)
			(layers "B.Cu" "B.Mask" "B.Paste")
			(net "DELTA_L_GND_1")
		)
		(zone
			(layers "F.Cu" "B.Cu" "In1.Cu" "In2.Cu" "In3.Cu" "In4.Cu" "In5.Cu" "In6.Cu"
				"In7.Cu" "In8.Cu" "In9.Cu" "In10.Cu" "In11.Cu" "In12.Cu" "In13.Cu" "In14.Cu"
				"In15.Cu" "In16.Cu"
			)
			(hatch none 0.5)
			(connect_pads
				(clearance 0)
			)
			(min_thickness 0.25)
			(keepout
				(tracks not_allowed)
				(vias allowed)
				(pads allowed)
				(copperpour not_allowed)
				(footprints allowed)
			)
			(placement
				(enabled no)
				(sheetname "")
			)
			(fill
				(thermal_gap 0.5)
				(thermal_bridge_width 0.5)
				(island_removal_mode 0)
			)
			(polygon
				(pts
					(arc
						(start 326.700388 1.653794)
						(mid 324.846188 1.653794)
						(end 326.700388 1.653794)
					)
				)
			)
		)
		(zone
			(layers "F.Cu" "B.Cu" "In1.Cu" "In2.Cu" "In3.Cu" "In4.Cu" "In5.Cu" "In6.Cu"
				"In7.Cu" "In8.Cu" "In9.Cu" "In10.Cu" "In11.Cu" "In12.Cu" "In13.Cu" "In14.Cu"
				"In15.Cu" "In16.Cu"
			)
			(hatch none 0.5)
			(connect_pads
				(clearance 0)
			)
			(min_thickness 0.25)
			(keepout
				(tracks not_allowed)
				(vias allowed)
				(pads allowed)
				(copperpour not_allowed)
				(footprints allowed)
			)
			(placement
				(enabled no)
				(sheetname "")
			)
			(fill
				(thermal_gap 0.5)
				(thermal_bridge_width 0.5)
				(island_removal_mode 0)
			)
			(polygon
				(pts
					(arc
						(start 326.700388 4.193794)
						(mid 324.846188 4.193794)
						(end 326.700388 4.193794)
					)
				)
			)
		)
		(zone
			(layers "F.Cu" "B.Cu" "In1.Cu" "In2.Cu" "In3.Cu" "In4.Cu" "In5.Cu" "In6.Cu"
				"In7.Cu" "In8.Cu" "In9.Cu" "In10.Cu" "In11.Cu" "In12.Cu" "In13.Cu" "In14.Cu"
				"In15.Cu" "In16.Cu"
			)
			(hatch none 0.5)
			(connect_pads
				(clearance 0)
			)
			(min_thickness 0.25)
			(keepout
				(tracks not_allowed)
				(vias allowed)
				(pads allowed)
				(copperpour not_allowed)
				(footprints allowed)
			)
			(placement
				(enabled no)
				(sheetname "")
			)
			(fill
				(thermal_gap 0.5)
				(thermal_bridge_width 0.5)
				(island_removal_mode 0)
			)
			(polygon
				(pts
					(arc
						(start 333.050388 1.653794)
						(mid 331.196188 1.653794)
						(end 333.050388 1.653794)
					)
				)
			)
		)
		(zone
			(layers "F.Cu" "B.Cu" "In1.Cu" "In2.Cu" "In3.Cu" "In4.Cu" "In5.Cu" "In6.Cu"
				"In7.Cu" "In8.Cu" "In9.Cu" "In10.Cu" "In11.Cu" "In12.Cu" "In13.Cu" "In14.Cu"
				"In15.Cu" "In16.Cu"
			)
			(hatch none 0.5)
			(connect_pads
				(clearance 0)
			)
			(min_thickness 0.25)
			(keepout
				(tracks not_allowed)
				(vias allowed)
				(pads allowed)
				(copperpour not_allowed)
				(footprints allowed)
			)
			(placement
				(enabled no)
				(sheetname "")
			)
			(fill
				(thermal_gap 0.5)
				(thermal_bridge_width 0.5)
				(island_removal_mode 0)
			)
			(polygon
				(pts
					(arc
						(start 333.050388 4.193794)
						(mid 331.196188 4.193794)
						(end 333.050388 4.193794)
					)
				)
			)
		)
		(zone
			(layer "B.Cu")
			(hatch none 0.5)
			(connect_pads
				(clearance 0)
			)
			(min_thickness 0.25)
			(keepout
				(tracks not_allowed)
				(vias allowed)
				(pads allowed)
				(copperpour not_allowed)
				(footprints allowed)
			)
			(placement
				(enabled no)
				(sheetname "")
			)
			(fill
				(thermal_gap 0.5)
				(thermal_bridge_width 0.5)
				(island_removal_mode 0)
			)
			(polygon
				(pts
					(xy 328.122788 2.375154) (xy 328.122788 2.470658) (xy 328.719688 2.470658) (xy 328.719688 2.877058)
					(xy 328.122788 2.877058) (xy 328.122788 2.97053) (xy 328.719688 2.97053) (xy 328.719688 3.37693)
					(xy 328.122788 3.37693) (xy 328.122788 3.472434) (xy 328.821288 3.472434) (xy 328.821288 2.375154)
				)
			)
		)
	)
	(footprint ""
		(layer "B.Cu")
		(at 504.058428 2.33172 90)
		(property "Reference" "X31"
			(at 1.48082 3.196082 270)
			(unlocked yes)
			(layer "B.SilkS")
			(effects
				(font
					(size 0.7874 0.5842)
					(thickness 0.1524)
				)
				(justify left mirror)
			)
		)
		(property "Value" ""
			(at 0 0 90)
			(layer "B.Fab")
			(effects
				(font
					(size 1.27 1.27)
				)
				(justify mirror)
			)
		)
		(property "Device Type" "TP_TDR_4P_FTS_TH-TP_TDR_4P_DIPA"
			(at -1.30175 1.27 0)
			(unlocked yes)
			(layer "B.Fab")
			(hide yes)
			(effects
				(font
					(size 0.635 0.4064)
					(thickness 0.1524)
				)
				(justify mirror)
			)
		)
		(property "User Part Number" "N_A"
			(at -1.30175 1.27 0)
			(unlocked yes)
			(layer "Cmts.User")
			(hide yes)
			(effects
				(font
					(size 0.635 0.4064)
					(thickness 0.1524)
				)
				(justify mirror)
			)
		)
		(duplicate_pad_numbers_are_jumpers no)
		(fp_line
			(start 0 -1.27)
			(end 0 -0.635)
			(stroke
				(width 0.1524)
				(type default)
			)
			(layer "B.SilkS")
		)
		(fp_line
			(start -2.54 -1.27)
			(end 0 -1.27)
			(stroke
				(width 0.1524)
				(type default)
			)
			(layer "B.SilkS")
		)
		(fp_line
			(start -2.54 -1.1303)
			(end -2.54 -1.27)
			(stroke
				(width 0.1524)
				(type default)
			)
			(layer "B.SilkS")
		)
		(fp_line
			(start 0 0.635)
			(end 0 1.905)
			(stroke
				(width 0.1524)
				(type default)
			)
			(layer "B.SilkS")
		)
		(fp_line
			(start -2.54 1.4097)
			(end -2.54 1.1303)
			(stroke
				(width 0.1524)
				(type default)
			)
			(layer "B.SilkS")
		)
		(fp_line
			(start 0 3.175)
			(end 0 3.81)
			(stroke
				(width 0.1524)
				(type default)
			)
			(layer "B.SilkS")
		)
		(fp_line
			(start 0 3.81)
			(end -2.54 3.81)
			(stroke
				(width 0.1524)
				(type default)
			)
			(layer "B.SilkS")
		)
		(fp_line
			(start -2.54 3.81)
			(end -2.54 3.6703)
			(stroke
				(width 0.1524)
				(type default)
			)
			(layer "B.SilkS")
		)
		(fp_poly
			(pts
				(xy 2.285746 -0.762) (xy 2.285746 0.762) (xy 0.761746 0)
			)
			(stroke
				(width 0)
				(type default)
			)
			(fill yes)
			(layer "B.SilkS")
		)
		(fp_line
			(start 0 -1.27)
			(end 0 3.81)
			(stroke
				(width 0.1)
				(type default)
			)
			(layer "B.Fab")
		)
		(fp_line
			(start -2.54 -1.27)
			(end 0 -1.27)
			(stroke
				(width 0.1)
				(type default)
			)
			(layer "B.Fab")
		)
		(fp_line
			(start 0 3.81)
			(end -2.54 3.81)
			(stroke
				(width 0.1)
				(type default)
			)
			(layer "B.Fab")
		)
		(fp_line
			(start -2.54 3.81)
			(end -2.54 -1.27)
			(stroke
				(width 0.1)
				(type default)
			)
			(layer "B.Fab")
		)
		(fp_poly
			(pts
				(xy 0.761746 0) (xy 2.285746 -0.762) (xy 2.285746 0.762)
			)
			(stroke
				(width 0)
				(type default)
			)
			(fill yes)
			(layer "B.Fab")
		)
		(pad "1" thru_hole circle
			(at 0 0 270)
			(size 1.0033 1.0033)
			(drill 0.249936)
			(layers "*.Cu" "*.Mask")
			(remove_unused_layers no)
			(net "TDR_DIFF_100_IN5_DN")
			(clearance 0.10795)
			(padstack
				(mode front_inner_back)
				(layer "Inner"
					(shape circle)
					(size 0.8001 0.8001)
					(clearance 0.1524)
				)
				(layer "B.Cu"
					(shape circle)
					(size 1.0033 1.0033)
					(thermal_gap 0.10795)
					(clearance 0.10795)
				)
			)
		)
		(pad "2" thru_hole circle
			(at -2.54 0 270)
			(size 1.9939 1.9939)
			(drill 0.249936)
			(layers "*.Cu" "*.Mask")
			(remove_unused_layers no)
			(net "T1_GND")
			(clearance 0.10795)
			(padstack
				(mode front_inner_back)
				(layer "Inner"
					(shape circle)
					(size 0.8001 0.8001)
					(clearance 0.1524)
				)
				(layer "B.Cu"
					(shape circle)
					(size 1.9939 1.9939)
					(thermal_gap 0.10795)
					(clearance 0.10795)
				)
			)
		)
		(pad "3" thru_hole circle
			(at -2.54 2.54 270)
			(size 1.9939 1.9939)
			(drill 0.249936)
			(layers "*.Cu" "*.Mask")
			(remove_unused_layers no)
			(net "T1_GND")
			(clearance 0.10795)
			(padstack
				(mode front_inner_back)
				(layer "Inner"
					(shape circle)
					(size 0.8001 0.8001)
					(clearance 0.1524)
				)
				(layer "B.Cu"
					(shape circle)
					(size 1.9939 1.9939)
					(thermal_gap 0.10795)
					(clearance 0.10795)
				)
			)
		)
		(pad "4" thru_hole circle
			(at 0 2.54 270)
			(size 1.0033 1.0033)
			(drill 0.249936)
			(layers "*.Cu" "*.Mask")
			(remove_unused_layers no)
			(net "TDR_DIFF_100_IN5_DP")
			(clearance 0.10795)
			(padstack
				(mode front_inner_back)
				(layer "Inner"
					(shape circle)
					(size 0.8001 0.8001)
					(clearance 0.1524)
				)
				(layer "B.Cu"
					(shape circle)
					(size 1.0033 1.0033)
					(thermal_gap 0.10795)
					(clearance 0.10795)
				)
			)
		)
	)
)
